# T6G (Grand Teton) — schematic netlist excerpt (pin names and nets, part order shuffled) for the footprints in the layout excerpt that follows; sources: Cadence DE-HDL packaged netlist, KiCad conversion of 04192023_DAF0TMB3IC0_F0TG_MB_C_brd_V02_OCP.brd

R3816  Q_RES  100K 1% CHIP  pkg 0402LF  page 140 : A = P3V3_AUX ; B = P12V_OCP_FAULT_2
R2346  Q_RES  100K 1% CHIP  pkg 0402LF  page 85 : A = P3V3_AUX ; B = PWRGD_P5V_AUX_R2

(kicad_pcb
	(version 20260206)
	(generator "pcbnew")
	(generator_version "10.0")
	(general
		(thickness 1.6)
		(legacy_teardrops no)
	)
	(paper "A4")
	(title_block
		(title "04192023_DAF0TMB3IC0_F0TG_MB_C_brd_V02_OCP.brd")
		(comment 1 "Grand Teton / footprints 2864-2865 of 8354")
	)
	(layers
		(0 "F.Cu" signal "TOP")
		(4 "In1.Cu" signal "GND")
		(6 "In2.Cu" signal "IN1")
		(8 "In3.Cu" signal "GND1")
		(10 "In4.Cu" signal "IN2")
		(12 "In5.Cu" signal "GND2")
		(14 "In6.Cu" signal "IN3")
		(16 "In7.Cu" signal "GND3")
		(18 "In8.Cu" signal "VCC")
		(20 "In9.Cu" signal "VCC1")
		(22 "In10.Cu" signal "GND4")
		(24 "In11.Cu" signal "IN4")
		(26 "In12.Cu" signal "GND5")
		(28 "In13.Cu" signal "IN5")
		(30 "In14.Cu" signal "GND6")
		(32 "In15.Cu" signal "IN6")
		(34 "In16.Cu" signal "GND7")
		(2 "B.Cu" signal "BOTTOM")
		(9 "F.Adhes" user "F.Adhesive")
		(11 "B.Adhes" user "B.Adhesive")
		(13 "F.Paste" user "Package Geometry/Pastemask Top")
		(15 "B.Paste" user "Package Geometry/Pastemask Bottom")
		(5 "F.SilkS" user "Ref Des/Silkscreen Top")
		(7 "B.SilkS" user "Ref Des/Silkscreen Bottom")
		(1 "F.Mask" user "Board Geometry/Soldermask Top")
		(3 "B.Mask" user "Board Geometry/Soldermask Bottom")
		(17 "Dwgs.User" user "User.Drawings")
		(19 "Cmts.User" user "User.Comments")
		(21 "Eco1.User" user "User.Eco1")
		(23 "Eco2.User" user "User.Eco2")
		(25 "Edge.Cuts" user "Board Geometry/Outline")
		(27 "Margin" user)
		(31 "F.CrtYd" user "Package Geometry/Place Bound Top")
		(29 "B.CrtYd" user "Package Geometry/Place Bound Bottom")
		(35 "F.Fab" user "Ref Des/Assembly Top")
		(33 "B.Fab" user "Ref Des/Assembly Bottom")
	)
	(footprint ""
		(layer "F.Cu")
		(at 406.475946 -136.231376 180)
		(property "Reference" "R2346"
			(at 0 0 180)
			(layer "F.SilkS")
			(hide yes)
			(effects
				(font
					(size 1.27 1.27)
				)
			)
		)
		(property "Value" ""
			(at 0 0 180)
			(layer "F.Fab")
			(effects
				(font
					(size 1.27 1.27)
				)
			)
		)
		(duplicate_pad_numbers_are_jumpers no)
		(fp_line
			(start 0.7874 0.4064)
			(end -0.7874 0.4064)
			(stroke
				(width 0.1524)
				(type default)
			)
			(layer "F.SilkS")
		)
		(fp_line
			(start 0.7874 -0.4064)
			(end 0.7874 0.4064)
			(stroke
				(width 0.1524)
				(type default)
			)
			(layer "F.SilkS")
		)
		(fp_line
			(start -0.7874 0.4064)
			(end -0.7874 -0.4064)
			(stroke
				(width 0.1524)
				(type default)
			)
			(layer "F.SilkS")
		)
		(fp_line
			(start -0.7874 -0.4064)
			(end 0.7874 -0.4064)
			(stroke
				(width 0.1524)
				(type default)
			)
			(layer "F.SilkS")
		)
		(fp_line
			(start 0.67945 0.3048)
			(end 0.120396 0.3048)
			(stroke
				(width 0.1)
				(type default)
			)
			(layer "F.Fab")
		)
		(fp_line
			(start 0.67945 -0.3048)
			(end 0.67945 0.3048)
			(stroke
				(width 0.1)
				(type default)
			)
			(layer "F.Fab")
		)
		(fp_line
			(start 0.12065 -0.2794)
			(end 0.12065 -0.3048)
			(stroke
				(width 0.1)
				(type default)
			)
			(layer "F.Fab")
		)
		(fp_line
			(start 0.12065 -0.3048)
			(end 0.67945 -0.3048)
			(stroke
				(width 0.1)
				(type default)
			)
			(layer "F.Fab")
		)
		(fp_line
			(start 0.120396 0.3048)
			(end 0.120396 0.2794)
			(stroke
				(width 0.1)
				(type default)
			)
			(layer "F.Fab")
		)
		(fp_line
			(start 0.120396 0.2794)
			(end -0.12065 0.2794)
			(stroke
				(width 0.1)
				(type default)
			)
			(layer "F.Fab")
		)
		(fp_line
			(start -0.12065 0.3048)
			(end -0.67945 0.3048)
			(stroke
				(width 0.1)
				(type default)
			)
			(layer "F.Fab")
		)
		(fp_line
			(start -0.12065 0.2794)
			(end -0.12065 0.3048)
			(stroke
				(width 0.1)
				(type default)
			)
			(layer "F.Fab")
		)
		(fp_line
			(start -0.12065 -0.2794)
			(end 0.12065 -0.2794)
			(stroke
				(width 0.1)
				(type default)
			)
			(layer "F.Fab")
		)
		(fp_line
			(start -0.12065 -0.305054)
			(end -0.12065 -0.2794)
			(stroke
				(width 0.1)
				(type default)
			)
			(layer "F.Fab")
		)
		(fp_line
			(start -0.67945 0.3048)
			(end -0.67945 -0.305054)
			(stroke
				(width 0.1)
				(type default)
			)
			(layer "F.Fab")
		)
		(fp_line
			(start -0.67945 -0.305054)
			(end -0.12065 -0.305054)
			(stroke
				(width 0.1)
				(type default)
			)
			(layer "F.Fab")
		)
		(pad "1" smd circle
			(at -0.40005 0 180)
			(size 0 0)
			(layers "F.Cu" "F.Mask" "F.Paste")
			(net "P3V3_AUX")
		)
		(pad "2" smd circle
			(at 0.40005 0 180)
			(size 0 0)
			(layers "F.Cu" "F.Mask" "F.Paste")
			(net "PWRGD_P5V_AUX_R2")
		)
	)
	(footprint ""
		(layer "F.Cu")
		(at 82.706718 -21.016722 90)
		(property "Reference" "R3816"
			(at 0 0 90)
			(layer "F.SilkS")
			(hide yes)
			(effects
				(font
					(size 1.27 1.27)
				)
			)
		)
		(property "Value" ""
			(at 0 0 90)
			(layer "F.Fab")
			(effects
				(font
					(size 1.27 1.27)
				)
			)
		)
		(duplicate_pad_numbers_are_jumpers no)
		(fp_line
			(start 0.7874 -0.4064)
			(end 0.7874 0.4064)
			(stroke
				(width 0.1524)
				(type default)
			)
			(layer "F.SilkS")
		)
		(fp_line
			(start -0.7874 -0.4064)
			(end 0.7874 -0.4064)
			(stroke
				(width 0.1524)
				(type default)
			)
			(layer "F.SilkS")
		)
		(fp_line
			(start 0.7874 0.4064)
			(end -0.7874 0.4064)
			(stroke
				(width 0.1524)
				(type default)
			)
			(layer "F.SilkS")
		)
		(fp_line
			(start -0.7874 0.4064)
			(end -0.7874 -0.4064)
			(stroke
				(width 0.1524)
				(type default)
			)
			(layer "F.SilkS")
		)
		(fp_line
			(start -0.12065 -0.305054)
			(end -0.12065 -0.2794)
			(stroke
				(width 0.1)
				(type default)
			)
			(layer "F.Fab")
		)
		(fp_line
			(start -0.67945 -0.305054)
			(end -0.12065 -0.305054)
			(stroke
				(width 0.1)
				(type default)
			)
			(layer "F.Fab")
		)
		(fp_line
			(start 0.67945 -0.3048)
			(end 0.67945 0.3048)
			(stroke
				(width 0.1)
				(type default)
			)
			(layer "F.Fab")
		)
		(fp_line
			(start 0.12065 -0.3048)
			(end 0.67945 -0.3048)
			(stroke
				(width 0.1)
				(type default)
			)
			(layer "F.Fab")
		)
		(fp_line
			(start 0.12065 -0.2794)
			(end 0.12065 -0.3048)
			(stroke
				(width 0.1)
				(type default)
			)
			(layer "F.Fab")
		)
		(fp_line
			(start -0.12065 -0.2794)
			(end 0.12065 -0.2794)
			(stroke
				(width 0.1)
				(type default)
			)
			(layer "F.Fab")
		)
		(fp_line
			(start 0.120396 0.2794)
			(end -0.12065 0.2794)
			(stroke
				(width 0.1)
				(type default)
			)
			(layer "F.Fab")
		)
		(fp_line
			(start -0.12065 0.2794)
			(end -0.12065 0.3048)
			(stroke
				(width 0.1)
				(type default)
			)
			(layer "F.Fab")
		)
		(fp_line
			(start 0.67945 0.3048)
			(end 0.120396 0.3048)
			(stroke
				(width 0.1)
				(type default)
			)
			(layer "F.Fab")
		)
		(fp_line
			(start 0.120396 0.3048)
			(end 0.120396 0.2794)
			(stroke
				(width 0.1)
				(type default)
			)
			(layer "F.Fab")
		)
		(fp_line
			(start -0.12065 0.3048)
			(end -0.67945 0.3048)
			(stroke
				(width 0.1)
				(type default)
			)
			(layer "F.Fab")
		)
		(fp_line
			(start -0.67945 0.3048)
			(end -0.67945 -0.305054)
			(stroke
				(width 0.1)
				(type default)
			)
			(layer "F.Fab")
		)
		(pad "1" smd circle
			(at -0.40005 0 90)
			(size 0 0)
			(layers "F.Cu" "F.Mask" "F.Paste")
			(net "P3V3_AUX")
		)
		(pad "2" smd circle
			(at 0.40005 0 90)
			(size 0 0)
			(layers "F.Cu" "F.Mask" "F.Paste")
			(net "P12V_OCP_FAULT_2")
		)
	)
)
